# T6G (Grand Teton) — schematic netlist excerpt (pin names and nets, part order shuffled) for the footprints in the layout excerpt that follows; sources: Cadence DE-HDL packaged netlist, KiCad conversion of 04192023_DAF0TMB3IC0_F0TG_MB_C_brd_V02_OCP.brd

C6565  Q_CAP_DIFFBUS  DIFF BUS_0.22UF 6.3V 20% X6S  pkg C0201  page 297 : \1\ = P5E_CPU0_P2_TX_BUF_C_DP<0> ; \2\ = P5E_CPU0_P2_TX_BUF_DP<0>
C2446  Q_CAP  22UF 4V 20% X6S  pkg C0402  page 74 : A = PVDDCR_SOC_P1 ; B = GND
R4064  Q_RES  0 5% CHIP  pkg 0402LF  page 146 : A = E1S_0_P12V_EN ; B = P12V_E1S_EN_0_R

(kicad_pcb
	(version 20260206)
	(generator "pcbnew")
	(generator_version "10.0")
	(general
		(thickness 1.6)
		(legacy_teardrops no)
	)
	(paper "A4")
	(title_block
		(title "04192023_DAF0TMB3IC0_F0TG_MB_C_brd_V02_OCP.brd")
		(comment 1 "Grand Teton / footprints 1787-1789 of 8354")
	)
	(layers
		(0 "F.Cu" signal "TOP")
		(4 "In1.Cu" signal "GND")
		(6 "In2.Cu" signal "IN1")
		(8 "In3.Cu" signal "GND1")
		(10 "In4.Cu" signal "IN2")
		(12 "In5.Cu" signal "GND2")
		(14 "In6.Cu" signal "IN3")
		(16 "In7.Cu" signal "GND3")
		(18 "In8.Cu" signal "VCC")
		(20 "In9.Cu" signal "VCC1")
		(22 "In10.Cu" signal "GND4")
		(24 "In11.Cu" signal "IN4")
		(26 "In12.Cu" signal "GND5")
		(28 "In13.Cu" signal "IN5")
		(30 "In14.Cu" signal "GND6")
		(32 "In15.Cu" signal "IN6")
		(34 "In16.Cu" signal "GND7")
		(2 "B.Cu" signal "BOTTOM")
		(9 "F.Adhes" user "F.Adhesive")
		(11 "B.Adhes" user "B.Adhesive")
		(13 "F.Paste" user "Package Geometry/Pastemask Top")
		(15 "B.Paste" user "Package Geometry/Pastemask Bottom")
		(5 "F.SilkS" user "Ref Des/Silkscreen Top")
		(7 "B.SilkS" user "Ref Des/Silkscreen Bottom")
		(1 "F.Mask" user "Board Geometry/Soldermask Top")
		(3 "B.Mask" user "Board Geometry/Soldermask Bottom")
		(17 "Dwgs.User" user "User.Drawings")
		(19 "Cmts.User" user "User.Comments")
		(21 "Eco1.User" user "User.Eco1")
		(23 "Eco2.User" user "User.Eco2")
		(25 "Edge.Cuts" user "Board Geometry/Outline")
		(27 "Margin" user)
		(31 "F.CrtYd" user "Package Geometry/Place Bound Top")
		(29 "B.CrtYd" user "Package Geometry/Place Bound Bottom")
		(35 "F.Fab" user "Ref Des/Assembly Top")
		(33 "B.Fab" user "Ref Des/Assembly Bottom")
	)
	(footprint ""
		(layer "F.Cu")
		(at 112.425988 -256.012442 90)
		(property "Reference" "C2446"
			(at 0 0 90)
			(layer "F.SilkS")
			(hide yes)
			(effects
				(font
					(size 1.27 1.27)
				)
			)
		)
		(property "Value" ""
			(at 0 0 90)
			(layer "F.Fab")
			(effects
				(font
					(size 1.27 1.27)
				)
			)
		)
		(duplicate_pad_numbers_are_jumpers no)
		(fp_line
			(start 0.7874 -0.4064)
			(end 0.7874 0.4064)
			(stroke
				(width 0.1524)
				(type default)
			)
			(layer "F.SilkS")
		)
		(fp_line
			(start -0.7874 -0.4064)
			(end 0.7874 -0.4064)
			(stroke
				(width 0.1524)
				(type default)
			)
			(layer "F.SilkS")
		)
		(fp_line
			(start 0.7874 0.4064)
			(end -0.7874 0.4064)
			(stroke
				(width 0.1524)
				(type default)
			)
			(layer "F.SilkS")
		)
		(fp_line
			(start -0.7874 0.4064)
			(end -0.7874 -0.4064)
			(stroke
				(width 0.1524)
				(type default)
			)
			(layer "F.SilkS")
		)
		(fp_line
			(start -0.12065 -0.305054)
			(end -0.12065 -0.2794)
			(stroke
				(width 0.1)
				(type default)
			)
			(layer "F.Fab")
		)
		(fp_line
			(start -0.67945 -0.305054)
			(end -0.12065 -0.305054)
			(stroke
				(width 0.1)
				(type default)
			)
			(layer "F.Fab")
		)
		(fp_line
			(start 0.67945 -0.3048)
			(end 0.67945 0.3048)
			(stroke
				(width 0.1)
				(type default)
			)
			(layer "F.Fab")
		)
		(fp_line
			(start 0.12065 -0.3048)
			(end 0.67945 -0.3048)
			(stroke
				(width 0.1)
				(type default)
			)
			(layer "F.Fab")
		)
		(fp_line
			(start 0.12065 -0.2794)
			(end 0.12065 -0.3048)
			(stroke
				(width 0.1)
				(type default)
			)
			(layer "F.Fab")
		)
		(fp_line
			(start -0.12065 -0.2794)
			(end 0.12065 -0.2794)
			(stroke
				(width 0.1)
				(type default)
			)
			(layer "F.Fab")
		)
		(fp_line
			(start 0.120396 0.2794)
			(end -0.12065 0.2794)
			(stroke
				(width 0.1)
				(type default)
			)
			(layer "F.Fab")
		)
		(fp_line
			(start -0.12065 0.2794)
			(end -0.12065 0.3048)
			(stroke
				(width 0.1)
				(type default)
			)
			(layer "F.Fab")
		)
		(fp_line
			(start 0.67945 0.3048)
			(end 0.120396 0.3048)
			(stroke
				(width 0.1)
				(type default)
			)
			(layer "F.Fab")
		)
		(fp_line
			(start 0.120396 0.3048)
			(end 0.120396 0.2794)
			(stroke
				(width 0.1)
				(type default)
			)
			(layer "F.Fab")
		)
		(fp_line
			(start -0.12065 0.3048)
			(end -0.67945 0.3048)
			(stroke
				(width 0.1)
				(type default)
			)
			(layer "F.Fab")
		)
		(fp_line
			(start -0.67945 0.3048)
			(end -0.67945 -0.305054)
			(stroke
				(width 0.1)
				(type default)
			)
			(layer "F.Fab")
		)
		(pad "1" smd circle
			(at -0.40005 0 90)
			(size 0 0)
			(layers "F.Cu" "F.Mask" "F.Paste")
			(net "PVDDCR_SOC_P1")
		)
		(pad "2" smd circle
			(at 0.40005 0 90)
			(size 0 0)
			(layers "F.Cu" "F.Mask" "F.Paste")
			(net "GND")
		)
	)
	(footprint ""
		(layer "F.Cu")
		(at 371.681502 -414.636458 -90)
		(property "Reference" "C6565"
			(at 0 0 270)
			(layer "F.SilkS")
			(hide yes)
			(effects
				(font
					(size 1.27 1.27)
				)
			)
		)
		(property "Value" ""
			(at 0 0 270)
			(layer "F.Fab")
			(effects
				(font
					(size 1.27 1.27)
				)
			)
		)
		(duplicate_pad_numbers_are_jumpers no)
		(fp_line
			(start -0.299974 0.150114)
			(end -0.299974 -0.150114)
			(stroke
				(width 0.1)
				(type default)
			)
			(layer "F.Fab")
		)
		(fp_line
			(start 0.299974 0.150114)
			(end -0.299974 0.150114)
			(stroke
				(width 0.1)
				(type default)
			)
			(layer "F.Fab")
		)
		(fp_line
			(start -0.299974 -0.150114)
			(end 0.299974 -0.150114)
			(stroke
				(width 0.1)
				(type default)
			)
			(layer "F.Fab")
		)
		(fp_line
			(start 0.299974 -0.150114)
			(end 0.299974 0.150114)
			(stroke
				(width 0.1)
				(type default)
			)
			(layer "F.Fab")
		)
		(pad "1" smd rect
			(at -0.2667 0 270)
			(size 0.3048 0.381)
			(layers "F.Cu" "F.Mask" "F.Paste")
			(net "P5E_CPU0_P2_TX_BUF_C_DP<0>")
		)
		(pad "2" smd rect
			(at 0.2667 0 270)
			(size 0.3048 0.381)
			(layers "F.Cu" "F.Mask" "F.Paste")
			(net "P5E_CPU0_P2_TX_BUF_DP<0>")
		)
	)
	(footprint ""
		(layer "F.Cu")
		(at 250.55957 -66.238374)
		(property "Reference" "R4064"
			(at 0 0 0)
			(layer "F.SilkS")
			(hide yes)
			(effects
				(font
					(size 1.27 1.27)
				)
			)
		)
		(property "Value" ""
			(at 0 0 0)
			(layer "F.Fab")
			(effects
				(font
					(size 1.27 1.27)
				)
			)
		)
		(duplicate_pad_numbers_are_jumpers no)
		(fp_line
			(start -0.7874 -0.4064)
			(end 0.7874 -0.4064)
			(stroke
				(width 0.1524)
				(type default)
			)
			(layer "F.SilkS")
		)
		(fp_line
			(start -0.7874 0.4064)
			(end -0.7874 -0.4064)
			(stroke
				(width 0.1524)
				(type default)
			)
			(layer "F.SilkS")
		)
		(fp_line
			(start 0.7874 -0.4064)
			(end 0.7874 0.4064)
			(stroke
				(width 0.1524)
				(type default)
			)
			(layer "F.SilkS")
		)
		(fp_line
			(start 0.7874 0.4064)
			(end -0.7874 0.4064)
			(stroke
				(width 0.1524)
				(type default)
			)
			(layer "F.SilkS")
		)
		(fp_line
			(start -0.67945 -0.305054)
			(end -0.12065 -0.305054)
			(stroke
				(width 0.1)
				(type default)
			)
			(layer "F.Fab")
		)
		(fp_line
			(start -0.67945 0.3048)
			(end -0.67945 -0.305054)
			(stroke
				(width 0.1)
				(type default)
			)
			(layer "F.Fab")
		)
		(fp_line
			(start -0.12065 -0.305054)
			(end -0.12065 -0.2794)
			(stroke
				(width 0.1)
				(type default)
			)
			(layer "F.Fab")
		)
		(fp_line
			(start -0.12065 -0.2794)
			(end 0.12065 -0.2794)
			(stroke
				(width 0.1)
				(type default)
			)
			(layer "F.Fab")
		)
		(fp_line
			(start -0.12065 0.2794)
			(end -0.12065 0.3048)
			(stroke
				(width 0.1)
				(type default)
			)
			(layer "F.Fab")
		)
		(fp_line
			(start -0.12065 0.3048)
			(end -0.67945 0.3048)
			(stroke
				(width 0.1)
				(type default)
			)
			(layer "F.Fab")
		)
		(fp_line
			(start 0.120396 0.2794)
			(end -0.12065 0.2794)
			(stroke
				(width 0.1)
				(type default)
			)
			(layer "F.Fab")
		)
		(fp_line
			(start 0.120396 0.3048)
			(end 0.120396 0.2794)
			(stroke
				(width 0.1)
				(type default)
			)
			(layer "F.Fab")
		)
		(fp_line
			(start 0.12065 -0.3048)
			(end 0.67945 -0.3048)
			(stroke
				(width 0.1)
				(type default)
			)
			(layer "F.Fab")
		)
		(fp_line
			(start 0.12065 -0.2794)
			(end 0.12065 -0.3048)
			(stroke
				(width 0.1)
				(type default)
			)
			(layer "F.Fab")
		)
		(fp_line
			(start 0.67945 -0.3048)
			(end 0.67945 0.3048)
			(stroke
				(width 0.1)
				(type default)
			)
			(layer "F.Fab")
		)
		(fp_line
			(start 0.67945 0.3048)
			(end 0.120396 0.3048)
			(stroke
				(width 0.1)
				(type default)
			)
			(layer "F.Fab")
		)
		(pad "1" smd circle
			(at -0.40005 0)
			(size 0 0)
			(layers "F.Cu" "F.Mask" "F.Paste")
			(net "E1S_0_P12V_EN")
		)
		(pad "2" smd circle
			(at 0.40005 0)
			(size 0 0)
			(layers "F.Cu" "F.Mask" "F.Paste")
			(net "P12V_E1S_EN_0_R")
		)
	)
)
